# BASEBOARD_FAB2 (Tioga Pass) — schematic netlist excerpt (pin names and nets, part order shuffled) for the footprints in the layout excerpt that follows; sources: Cadence DE-HDL packaged netlist, KiCad conversion of Wiwynn_Tioga_Pass_MB.brd

EU1F1  IR354XX  IR35411 IC  pkg SM  page 224
  VOS  = PVDDQ_GHJ
  LGND  = GND
  VCC  = VR_PVDDQ_GHJ_PH2_VCIN
  VDRV  = P5V_STBY
  PGND(0)  = GND
  GL(0)  = TP_PVDDQ_GHJ_PH2_GL_0
  PGND(1)  = GND
  SW  = VR_PVDDQ_GHJ_PH2_SW
  VIN(0)  = VR_FET_SW_P12V_STBY_PVDDQ_GHJ
  VIN(1)  = VR_FET_SW_P12V_STBY_PVDDQ_GHJ
  NC  = NC
  PHASE  = VR_PVDDQ_GHJ_PH2_PHASE
  BOOST  = VR_PVDDQ_GHJ_PH2_BOOT_R
  PWM  = VR_PVDDQ_GHJ_PWM2
  EN  = P5V_STBY
  TOUT_FLT  = A_TSENSE_PVDDQ_GHJ
  OCSET  = VR_PVDDQ_GHJ_PH2_OCSET
  IOUT  = ISENSE_PVDDQ_GHJ_PH2_IMON
  REFIN  = VR_PVDDQ_GHJ_AIREF2
  PGND(2)  = GND
  GL(1)  = TP_PVDDQ_GHJ_PH2_GL_1

(kicad_pcb
	(version 20260206)
	(generator "pcbnew")
	(generator_version "10.0")
	(general
		(thickness 1.6)
		(legacy_teardrops no)
	)
	(paper "A4")
	(title_block
		(title "Wiwynn_Tioga_Pass_MB.brd")
		(comment 1 "Tioga Pass / footprints 1950-1950 of 4770")
	)
	(layers
		(0 "F.Cu" signal "TOP")
		(4 "In1.Cu" signal "L2GND")
		(6 "In2.Cu" signal "L3")
		(8 "In3.Cu" signal "L4GND")
		(10 "In4.Cu" signal "L5")
		(12 "In5.Cu" signal "L6GND")
		(14 "In6.Cu" signal "L7VCC")
		(16 "In7.Cu" signal "L8VCC")
		(18 "In8.Cu" signal "L9GND")
		(20 "In9.Cu" signal "L10")
		(22 "In10.Cu" signal "L11GND")
		(24 "In11.Cu" signal "L12")
		(26 "In12.Cu" signal "L13GND")
		(2 "B.Cu" signal "BOTTOM")
		(9 "F.Adhes" user "F.Adhesive")
		(11 "B.Adhes" user "B.Adhesive")
		(13 "F.Paste" user "Package Geometry/Pastemask Top")
		(15 "B.Paste" user "Package Geometry/Pastemask Bottom")
		(5 "F.SilkS" user "Ref Des/Silkscreen Top")
		(7 "B.SilkS" user "Ref Des/Silkscreen Bottom")
		(1 "F.Mask" user "Board Geometry/Soldermask Top")
		(3 "B.Mask" user "Board Geometry/Soldermask Bottom")
		(17 "Dwgs.User" user "User.Drawings")
		(19 "Cmts.User" user "User.Comments")
		(21 "Eco1.User" user "User.Eco1")
		(23 "Eco2.User" user "User.Eco2")
		(25 "Edge.Cuts" user "Board Geometry/Outline")
		(27 "Margin" user)
		(31 "F.CrtYd" user "Package Geometry/Place Bound Top")
		(29 "B.CrtYd" user "Package Geometry/Place Bound Bottom")
		(35 "F.Fab" user "Ref Des/Assembly Top")
		(33 "B.Fab" user "Ref Des/Assembly Bottom")
	)
	(footprint ""
		(layer "F.Cu")
		(at 5.045456 -17.460976 90)
		(property "Reference" "EU1F1"
			(at 3.789172 1.463294 0)
			(unlocked yes)
			(layer "F.SilkS")
			(effects
				(font
					(size 0.7874 0.5842)
					(thickness 0.1524)
				)
			)
		)
		(property "Value" ""
			(at 0 0 90)
			(layer "F.Fab")
			(effects
				(font
					(size 1.27 1.27)
				)
			)
		)
		(duplicate_pad_numbers_are_jumpers no)
		(fp_line
			(start 2.9718 -3.5052)
			(end 2.9718 3.429)
			(stroke
				(width 0.1524)
				(type default)
			)
			(layer "F.SilkS")
		)
		(fp_line
			(start -3.0099 -3.5052)
			(end 2.9718 -3.5052)
			(stroke
				(width 0.1524)
				(type default)
			)
			(layer "F.SilkS")
		)
		(fp_line
			(start 2.9718 3.429)
			(end -3.0099 3.429)
			(stroke
				(width 0.1524)
				(type default)
			)
			(layer "F.SilkS")
		)
		(fp_line
			(start -3.0099 3.429)
			(end -3.0099 -3.5052)
			(stroke
				(width 0.1524)
				(type default)
			)
			(layer "F.SilkS")
		)
		(fp_circle
			(center -3.057398 -2.678684)
			(end -3.057398 -2.551684)
			(stroke
				(width 0.254)
				(type default)
			)
			(fill no)
			(layer "F.SilkS")
		)
		(fp_poly
			(pts
				(xy -2.9972 -3.4925) (xy -2.9972 -2.6924) (xy -2.1971 -3.4925)
			)
			(stroke
				(width 0)
				(type default)
			)
			(fill yes)
			(layer "F.SilkS")
		)
		(fp_poly
			(pts
				(xy -2.549906 -3.050032) (xy -2.549906 3.050032) (xy 2.549906 3.050032) (xy 2.549906 -3.050032)
			)
			(stroke
				(width 0)
				(type default)
			)
			(fill no)
			(layer "F.CrtYd")
		)
		(fp_line
			(start 2.549906 -3.050032)
			(end 2.549906 3.050032)
			(stroke
				(width 0.1)
				(type default)
			)
			(layer "F.Fab")
		)
		(fp_line
			(start -2.549906 -3.050032)
			(end 2.549906 -3.050032)
			(stroke
				(width 0.1)
				(type default)
			)
			(layer "F.Fab")
		)
		(fp_line
			(start 2.549906 3.050032)
			(end -2.549906 3.050032)
			(stroke
				(width 0.1)
				(type default)
			)
			(layer "F.Fab")
		)
		(fp_line
			(start -2.549906 3.050032)
			(end -2.549906 -3.050032)
			(stroke
				(width 0.1)
				(type default)
			)
			(layer "F.Fab")
		)
		(fp_circle
			(center -3.057398 -2.678684)
			(end -3.057398 -2.551684)
			(stroke
				(width 0.254)
				(type default)
			)
			(fill no)
			(layer "F.Fab")
		)
		(pad "1" smd rect
			(at -2.39522 -2.279904 90)
			(size 0.7112 0.254)
			(layers "F.Cu" "F.Mask" "F.Paste")
			(net "PVDDQ_GHJ")
		)
		(pad "2" smd rect
			(at -2.39522 -1.83007 90)
			(size 0.7112 0.254)
			(layers "F.Cu" "F.Mask" "F.Paste")
			(net "GND")
		)
		(pad "3" smd rect
			(at -2.39522 -1.379982 90)
			(size 0.7112 0.254)
			(layers "F.Cu" "F.Mask" "F.Paste")
			(net "VR_PVDDQ_GHJ_PH2_VCIN")
		)
		(pad "4" smd rect
			(at -2.39522 -0.929894 90)
			(size 0.7112 0.254)
			(layers "F.Cu" "F.Mask" "F.Paste")
			(net "P5V_STBY")
		)
		(pad "5" smd rect
			(at -2.39522 -0.48006 90)
			(size 0.7112 0.254)
			(layers "F.Cu" "F.Mask" "F.Paste")
			(net "GND")
		)
		(pad "6" smd rect
			(at -2.39522 -0.029972 90)
			(size 0.7112 0.254)
			(layers "F.Cu" "F.Mask" "F.Paste")
			(net "TP_PVDDQ_GHJ_PH2_GL_0")
		)
		(pad "7" smd custom
			(at 0.016764 1.145032 90)
			(size 0.53975 0.53975)
			(layers "F.Cu" "F.Mask" "F.Paste")
			(net "GND")
			(options
				(clearance outline)
				(anchor circle)
			)
			(primitives
				(gr_poly
					(pts
						(xy -2.7051 1.0795) (xy -2.7051 -0.3683) (xy -0.9271 -0.3683) (xy -0.9271 -1.0795) (xy 2.7051 -1.0795)
						(xy 2.7051 1.0795)
					)
					(width 0)
					(fill yes)
				)
			)
		)
		(pad "10" smd rect
			(at -0.008382 2.874772 90)
			(size 4.3434 0.6096)
			(layers "F.Cu" "F.Mask" "F.Paste")
			(net "VR_PVDDQ_GHJ_PH2_SW")
		)
		(pad "25" smd rect
			(at 1.548384 -1.283208 90)
			(size 2.3368 2.0066)
			(layers "F.Cu" "F.Mask" "F.Paste")
			(net "VR_FET_SW_P12V_STBY_PVDDQ_GHJ")
		)
		(pad "30" smd rect
			(at 2.050034 -2.895092 90)
			(size 0.254 0.7112)
			(layers "F.Cu" "F.Mask" "F.Paste")
			(net "VR_FET_SW_P12V_STBY_PVDDQ_GHJ")
		)
		(pad "31" smd rect
			(at 1.599946 -2.895092 90)
			(size 0.254 0.7112)
			(layers "F.Cu" "F.Mask" "F.Paste")
			(net "Net_297")
		)
		(pad "32" smd rect
			(at 1.150112 -2.895092 90)
			(size 0.254 0.7112)
			(layers "F.Cu" "F.Mask" "F.Paste")
			(net "VR_PVDDQ_GHJ_PH2_PHASE")
		)
		(pad "33" smd rect
			(at 0.700024 -2.895092 90)
			(size 0.254 0.7112)
			(layers "F.Cu" "F.Mask" "F.Paste")
			(net "VR_PVDDQ_GHJ_PH2_BOOT_R")
		)
		(pad "34" smd rect
			(at 0.249936 -2.895092 90)
			(size 0.254 0.7112)
			(layers "F.Cu" "F.Mask" "F.Paste")
			(net "VR_PVDDQ_GHJ_PWM2")
		)
		(pad "35" smd rect
			(at -0.199898 -2.895092 90)
			(size 0.254 0.7112)
			(layers "F.Cu" "F.Mask" "F.Paste")
			(net "P5V_STBY")
		)
		(pad "36" smd rect
			(at -0.649986 -2.895092 90)
			(size 0.254 0.7112)
			(layers "F.Cu" "F.Mask" "F.Paste")
			(net "A_TSENSE_PVDDQ_GHJ")
		)
		(pad "37" smd rect
			(at -1.100074 -2.895092 90)
			(size 0.254 0.7112)
			(layers "F.Cu" "F.Mask" "F.Paste")
			(net "VR_PVDDQ_GHJ_PH2_OCSET")
		)
		(pad "38" smd rect
			(at -1.549908 -2.895092 90)
			(size 0.254 0.7112)
			(layers "F.Cu" "F.Mask" "F.Paste")
			(net "ISENSE_PVDDQ_GHJ_PH2_IMON")
		)
		(pad "39" smd rect
			(at -1.999996 -2.895092 90)
			(size 0.254 0.7112)
			(layers "F.Cu" "F.Mask" "F.Paste")
			(net "VR_PVDDQ_GHJ_AIREF2")
		)
		(pad "40" smd rect
			(at -0.871728 -1.283208 90)
			(size 1.8034 2.0066)
			(layers "F.Cu" "F.Mask" "F.Paste")
			(net "GND")
		)
		(pad "41" smd rect
			(at -1.533906 0.247904 90)
			(size 0.508 0.3556)
			(layers "F.Cu" "F.Mask" "F.Paste")
			(net "TP_PVDDQ_GHJ_PH2_GL_1")
		)
	)
)
